(kicad_pcb
	(version 20260206)
	(generator "pcbnew")
	(generator_version "10.0")
	(general
		(thickness 1.6)
		(legacy_teardrops no)
	)
	(paper "A4")
	(title_block
		(title "v1-chassis-manager — T6M_CM_d_v01_1031_1645.brd")
		(comment 1 "Open CloudServer (Microsoft) / footprints 1577-1583 of 2512")
	)
	(layers
		(0 "F.Cu" signal "TOP")
		(4 "In1.Cu" signal "GND1")
		(6 "In2.Cu" signal "IN1")
		(8 "In3.Cu" signal "VCC1")
		(10 "In4.Cu" signal "VCC2")
		(12 "In5.Cu" signal "GND2")
		(14 "In6.Cu" signal "IN2")
		(16 "In7.Cu" signal "IN3")
		(18 "In8.Cu" signal "GND3")
		(2 "B.Cu" signal "BOTTOM")
		(9 "F.Adhes" user "F.Adhesive")
		(11 "B.Adhes" user "B.Adhesive")
		(13 "F.Paste" user "Package Geometry/Pastemask Top")
		(15 "B.Paste" user "Package Geometry/Pastemask Bottom")
		(5 "F.SilkS" user "Ref Des/Silkscreen Top")
		(7 "B.SilkS" user "Ref Des/Silkscreen Bottom")
		(1 "F.Mask" user "Board Geometry/Soldermask Top")
		(3 "B.Mask" user "Board Geometry/Soldermask Bottom")
		(17 "Dwgs.User" user "User.Drawings")
		(19 "Cmts.User" user "User.Comments")
		(21 "Eco1.User" user "User.Eco1")
		(23 "Eco2.User" user "User.Eco2")
		(25 "Edge.Cuts" user "Board Geometry/Outline")
		(27 "Margin" user)
		(31 "F.CrtYd" user "Package Geometry/Place Bound Top")
		(29 "B.CrtYd" user "Package Geometry/Place Bound Bottom")
		(35 "F.Fab" user "Ref Des/Assembly Top")
		(33 "B.Fab" user "Ref Des/Assembly Bottom")
	)
	(footprint ""
		(layer "B.Cu")
		(at 133.969252 -151.31415 90)
		(property "Reference" "C869"
			(at 1.2446 1.166876 270)
			(unlocked yes)
			(layer "B.SilkS")
			(effects
				(font
					(size 0.7874 0.5842)
					(thickness 0.1524)
				)
				(justify left mirror)
			)
		)
		(property "Value" ""
			(at 0 0 90)
			(layer "B.Fab")
			(effects
				(font
					(size 1.27 1.27)
				)
				(justify mirror)
			)
		)
		(duplicate_pad_numbers_are_jumpers no)
		(fp_line
			(start 0.7874 -0.4064)
			(end -0.7874 -0.4064)
			(stroke
				(width 0.1524)
				(type default)
			)
			(layer "B.SilkS")
		)
		(fp_line
			(start -0.7874 -0.4064)
			(end -0.7874 0.4064)
			(stroke
				(width 0.1524)
				(type default)
			)
			(layer "B.SilkS")
		)
		(fp_line
			(start 0 0.381)
			(end 0 -0.381)
			(stroke
				(width 0.1524)
				(type default)
			)
			(layer "B.SilkS")
		)
		(fp_line
			(start 0.7874 0.4064)
			(end 0.7874 -0.4064)
			(stroke
				(width 0.1524)
				(type default)
			)
			(layer "B.SilkS")
		)
		(fp_line
			(start -0.7874 0.4064)
			(end 0.7874 0.4064)
			(stroke
				(width 0.1524)
				(type default)
			)
			(layer "B.SilkS")
		)
		(fp_poly
			(pts
				(xy 0.5334 0.254) (xy 0.635 0.254) (xy 0.635 0.2286) (xy 0.635 -0.254) (xy 0.5334 -0.254) (xy 0.5334 -0.2794)
				(xy -0.5334 -0.2794) (xy -0.5334 -0.254) (xy -0.635 -0.254) (xy -0.635 0.254) (xy -0.5334 0.254)
				(xy -0.5334 0.2794) (xy 0.508 0.2794) (xy 0.5334 0.2794)
			)
			(stroke
				(width 0)
				(type default)
			)
			(fill no)
			(layer "B.CrtYd")
		)
		(pad "1" smd rect
			(at -0.40005 0 270)
			(size 0.4572 0.508)
			(layers "B.Cu" "B.Mask" "B.Paste")
			(net "P3V3_NODE1")
		)
		(pad "2" smd rect
			(at 0.40005 0 270)
			(size 0.4572 0.508)
			(layers "B.Cu" "B.Mask" "B.Paste")
			(net "GND")
		)
	)
	(footprint ""
		(layer "B.Cu")
		(at 39.650416 -97.068132 -90)
		(property "Reference" "R131"
			(at -0.973328 -0.017272 270)
			(unlocked yes)
			(layer "B.SilkS")
			(effects
				(font
					(size 0.7874 0.5842)
					(thickness 0.1524)
				)
				(justify left mirror)
			)
		)
		(property "Value" ""
			(at 0 0 90)
			(layer "B.Fab")
			(effects
				(font
					(size 1.27 1.27)
				)
				(justify mirror)
			)
		)
		(duplicate_pad_numbers_are_jumpers no)
		(fp_line
			(start -0.7874 0.4064)
			(end 0.7874 0.4064)
			(stroke
				(width 0.1524)
				(type default)
			)
			(layer "B.SilkS")
		)
		(fp_line
			(start 0.7874 0.4064)
			(end 0.7874 -0.4064)
			(stroke
				(width 0.1524)
				(type default)
			)
			(layer "B.SilkS")
		)
		(fp_line
			(start -0.7874 -0.4064)
			(end -0.7874 0.4064)
			(stroke
				(width 0.1524)
				(type default)
			)
			(layer "B.SilkS")
		)
		(fp_line
			(start 0.7874 -0.4064)
			(end -0.7874 -0.4064)
			(stroke
				(width 0.1524)
				(type default)
			)
			(layer "B.SilkS")
		)
		(fp_poly
			(pts
				(xy 0.508 0.2794) (xy 0.508 0.2286) (xy 0.635 0.2286) (xy 0.635 -0.254) (xy 0.5334 -0.254) (xy 0.5334 -0.2794)
				(xy -0.5334 -0.2794) (xy -0.5334 -0.254) (xy -0.635 -0.254) (xy -0.635 0.254) (xy -0.5334 0.254)
				(xy -0.5334 0.2794)
			)
			(stroke
				(width 0)
				(type default)
			)
			(fill no)
			(layer "B.CrtYd")
		)
		(pad "1" smd rect
			(at -0.40005 0 90)
			(size 0.4572 0.508)
			(layers "B.Cu" "B.Mask" "B.Paste")
			(net "P3V3_NODE1")
		)
		(pad "2" smd rect
			(at 0.40005 0 90)
			(size 0.4572 0.508)
			(layers "B.Cu" "B.Mask" "B.Paste")
			(net "SMB_CPU_NODE1_BMC_CLK")
		)
	)
	(footprint ""
		(layer "B.Cu")
		(at -11.397488 -59.063382 -90)
		(property "Reference" "J29"
			(at -6.14426 -2.971038 0)
			(unlocked yes)
			(layer "B.SilkS")
			(effects
				(font
					(size 0.7874 0.5842)
					(thickness 0.1524)
				)
				(justify left mirror)
			)
		)
		(property "Value" ""
			(at 0 0 90)
			(layer "B.Fab")
			(effects
				(font
					(size 1.27 1.27)
				)
				(justify mirror)
			)
		)
		(duplicate_pad_numbers_are_jumpers no)
		(fp_circle
			(center -4.064 0)
			(end -4.064 -0.635)
			(stroke
				(width 0.05)
				(type default)
			)
			(fill no)
			(layer "Edge.Cuts")
		)
		(fp_circle
			(center 0 0)
			(end 0 -0.635)
			(stroke
				(width 0.05)
				(type default)
			)
			(fill no)
			(layer "Edge.Cuts")
		)
		(fp_circle
			(center -4.064 -4.572)
			(end -4.064 -5.207)
			(stroke
				(width 0.05)
				(type default)
			)
			(fill no)
			(layer "Edge.Cuts")
		)
		(fp_circle
			(center 0 -4.572)
			(end 0 -5.207)
			(stroke
				(width 0.05)
				(type default)
			)
			(fill no)
			(layer "Edge.Cuts")
		)
		(fp_rect
			(start 1.27 1.27)
			(end -5.334 -5.842)
			(stroke
				(width 0)
				(type default)
			)
			(fill no)
			(layer "B.CrtYd")
		)
		(pad "" np_thru_hole circle
			(at -4.064 -4.572 90)
			(size 0.254 0.254)
			(drill 1.27)
			(layers "*.Cu" "*.Mask")
			(clearance 0.889)
			(thermal_gap 0.889)
		)
		(pad "" np_thru_hole circle
			(at -4.064 0 90)
			(size 0.254 0.254)
			(drill 1.27)
			(layers "*.Cu" "*.Mask")
			(clearance 0.889)
			(thermal_gap 0.889)
		)
		(pad "" np_thru_hole circle
			(at 0 -4.572 90)
			(size 0.254 0.254)
			(drill 1.27)
			(layers "*.Cu" "*.Mask")
			(clearance 0.889)
			(thermal_gap 0.889)
		)
		(pad "" np_thru_hole circle
			(at 0 0 90)
			(size 0.254 0.254)
			(drill 1.27)
			(layers "*.Cu" "*.Mask")
			(clearance 0.889)
			(thermal_gap 0.889)
		)
		(pad "1" thru_hole custom
			(at -1.397 -2.286)
			(size 0.139735 0.139735)
			(drill 0.254)
			(layers "*.Cu" "*.Mask")
			(remove_unused_layers no)
			(net "GND")
			(options
				(clearance outline)
				(anchor circle)
			)
			(primitives
				(gr_poly
					(pts
						(arc
							(start 0.26035 -0.1016)
							(mid 0 -0.279472)
							(end -0.26035 -0.1016)
						)
						(arc
							(start -0.50165 -0.1016)
							(mid -1.041472 0)
							(end -0.50165 0.1016)
						)
						(arc
							(start -0.26035 0.1016)
							(mid 0 0.279472)
							(end 0.26035 0.1016)
						)
						(arc
							(start 0.50165 0.1016)
							(mid 1.041472 0)
							(end 0.50165 -0.1016)
						)
					)
					(width 0)
					(fill yes)
				)
			)
			(padstack
				(mode front_inner_back)
				(layer "Inner"
					(shape custom)
					(size 0.139735 0.139735)
					(options
						(anchor circle)
					)
					(primitives
						(gr_poly
							(pts
								(arc
									(start 0.26035 -0.1016)
									(mid 0 -0.279472)
									(end -0.26035 -0.1016)
								)
								(arc
									(start -0.50165 -0.1016)
									(mid -1.041472 0)
									(end -0.50165 0.1016)
								)
								(arc
									(start -0.26035 0.1016)
									(mid 0 0.279472)
									(end 0.26035 0.1016)
								)
								(arc
									(start 0.50165 0.1016)
									(mid 1.041472 0)
									(end 0.50165 -0.1016)
								)
							)
							(width 0)
							(fill yes)
						)
					)
				)
				(layer "B.Cu"
					(shape custom)
					(size 0.266741 0.266741)
					(options
						(anchor circle)
					)
					(primitives
						(gr_poly
							(pts
								(xy -0.979932 -0.5334)
								(arc
									(start -0.979932 0.078994)
									(mid -0.925932 0.48038)
									(end -0.527812 0.4064)
								)
								(arc
									(start -0.234188 0.4064)
									(mid 0 0.53341)
									(end 0.234188 0.4064)
								)
								(arc
									(start 0.527812 0.4064)
									(mid 0.925878 0.480305)
									(end 0.979932 0.078994)
								)
								(xy 0.979932 -0.5334) (xy 0.548132 -0.5334) (xy 0.548132 -0.1016) (xy -0.548132 -0.1016) (xy -0.548132 -0.5334)
							)
							(width 0)
							(fill yes)
						)
					)
				)
			)
		)
		(pad "2" smd rect
			(at -2.032 -2.060956 90)
			(size 0.3048 0.2032)
			(layers "B.Cu" "B.Mask" "B.Paste")
			(net "BOT_85OHM")
		)
		(pad "3" smd rect
			(at -2.032 -2.511044 90)
			(size 0.3048 0.2032)
			(layers "B.Cu" "B.Mask" "B.Paste")
			(net "BOT_85OHM")
		)
		(zone
			(layers "F.Cu" "B.Cu" "In1.Cu" "In2.Cu" "In3.Cu" "In4.Cu" "In5.Cu" "In6.Cu"
				"In7.Cu" "In8.Cu"
			)
			(hatch none 0.5)
			(connect_pads
				(clearance 0)
			)
			(min_thickness 0.25)
			(keepout
				(tracks not_allowed)
				(vias allowed)
				(pads allowed)
				(copperpour not_allowed)
				(footprints allowed)
			)
			(placement
				(enabled no)
				(sheetname "")
			)
			(fill
				(thermal_gap 0.5)
				(thermal_bridge_width 0.5)
				(island_removal_mode 0)
			)
			(polygon
				(pts
					(arc
						(start -11.397488 -64.016382)
						(mid -11.397488 -62.238382)
						(end -11.397488 -64.016382)
					)
				)
			)
		)
		(zone
			(layers "F.Cu" "B.Cu" "In1.Cu" "In2.Cu" "In3.Cu" "In4.Cu" "In5.Cu" "In6.Cu"
				"In7.Cu" "In8.Cu"
			)
			(hatch none 0.5)
			(connect_pads
				(clearance 0)
			)
			(min_thickness 0.25)
			(keepout
				(tracks not_allowed)
				(vias allowed)
				(pads allowed)
				(copperpour not_allowed)
				(footprints allowed)
			)
			(placement
				(enabled no)
				(sheetname "")
			)
			(fill
				(thermal_gap 0.5)
				(thermal_bridge_width 0.5)
				(island_removal_mode 0)
			)
			(polygon
				(pts
					(arc
						(start -11.397488 -59.952382)
						(mid -11.397488 -58.174382)
						(end -11.397488 -59.952382)
					)
				)
			)
		)
		(zone
			(layers "F.Cu" "B.Cu" "In1.Cu" "In2.Cu" "In3.Cu" "In4.Cu" "In5.Cu" "In6.Cu"
				"In7.Cu" "In8.Cu"
			)
			(hatch none 0.5)
			(connect_pads
				(clearance 0)
			)
			(min_thickness 0.25)
			(keepout
				(tracks not_allowed)
				(vias allowed)
				(pads allowed)
				(copperpour not_allowed)
				(footprints allowed)
			)
			(placement
				(enabled no)
				(sheetname "")
			)
			(fill
				(thermal_gap 0.5)
				(thermal_bridge_width 0.5)
				(island_removal_mode 0)
			)
			(polygon
				(pts
					(arc
						(start -6.825488 -64.016382)
						(mid -6.825488 -62.238382)
						(end -6.825488 -64.016382)
					)
				)
			)
		)
		(zone
			(layers "F.Cu" "B.Cu" "In1.Cu" "In2.Cu" "In3.Cu" "In4.Cu" "In5.Cu" "In6.Cu"
				"In7.Cu" "In8.Cu"
			)
			(hatch none 0.5)
			(connect_pads
				(clearance 0)
			)
			(min_thickness 0.25)
			(keepout
				(tracks not_allowed)
				(vias allowed)
				(pads allowed)
				(copperpour not_allowed)
				(footprints allowed)
			)
			(placement
				(enabled no)
				(sheetname "")
			)
			(fill
				(thermal_gap 0.5)
				(thermal_bridge_width 0.5)
				(island_removal_mode 0)
			)
			(polygon
				(pts
					(arc
						(start -6.825488 -59.952382)
						(mid -6.825488 -58.174382)
						(end -6.825488 -59.952382)
					)
				)
			)
		)
	)
	(footprint ""
		(layer "B.Cu")
		(at 137.970006 -34.39541)
		(property "Reference" "R1186"
			(at -4.172458 18.515838 0)
			(unlocked yes)
			(layer "B.SilkS")
			(effects
				(font
					(size 0.7874 0.5842)
					(thickness 0.1524)
				)
				(justify left mirror)
			)
		)
		(property "Value" ""
			(at 0 0 0)
			(layer "B.Fab")
			(effects
				(font
					(size 1.27 1.27)
				)
				(justify mirror)
			)
		)
		(duplicate_pad_numbers_are_jumpers no)
		(fp_line
			(start -0.7874 -0.4064)
			(end -0.7874 0.4064)
			(stroke
				(width 0.1524)
				(type default)
			)
			(layer "B.SilkS")
		)
		(fp_line
			(start -0.7874 0.4064)
			(end 0.7874 0.4064)
			(stroke
				(width 0.1524)
				(type default)
			)
			(layer "B.SilkS")
		)
		(fp_line
			(start 0.7874 -0.4064)
			(end -0.7874 -0.4064)
			(stroke
				(width 0.1524)
				(type default)
			)
			(layer "B.SilkS")
		)
		(fp_line
			(start 0.7874 0.4064)
			(end 0.7874 -0.4064)
			(stroke
				(width 0.1524)
				(type default)
			)
			(layer "B.SilkS")
		)
		(fp_poly
			(pts
				(xy 0.508 0.2794) (xy 0.508 0.2286) (xy 0.635 0.2286) (xy 0.635 -0.254) (xy 0.5334 -0.254) (xy 0.5334 -0.2794)
				(xy -0.5334 -0.2794) (xy -0.5334 -0.254) (xy -0.635 -0.254) (xy -0.635 0.254) (xy -0.5334 0.254)
				(xy -0.5334 0.2794)
			)
			(stroke
				(width 0)
				(type default)
			)
			(fill no)
			(layer "B.CrtYd")
		)
		(pad "1" smd rect
			(at -0.40005 0 180)
			(size 0.4572 0.508)
			(layers "B.Cu" "B.Mask" "B.Paste")
			(net "SIO_CPLD_RSV3_R")
		)
		(pad "2" smd rect
			(at 0.40005 0 180)
			(size 0.4572 0.508)
			(layers "B.Cu" "B.Mask" "B.Paste")
			(net "GND")
		)
	)
	(footprint ""
		(layer "B.Cu")
		(at 40.36822 -153.70429)
		(property "Reference" "C417"
			(at -6.35127 -10.195814 0)
			(unlocked yes)
			(layer "B.SilkS")
			(effects
				(font
					(size 0.7874 0.5842)
					(thickness 0.1524)
				)
				(justify left mirror)
			)
		)
		(property "Value" ""
			(at 0 0 0)
			(layer "B.Fab")
			(effects
				(font
					(size 1.27 1.27)
				)
				(justify mirror)
			)
		)
		(duplicate_pad_numbers_are_jumpers no)
		(fp_line
			(start -0.7874 -0.4064)
			(end -0.7874 0.4064)
			(stroke
				(width 0.1524)
				(type default)
			)
			(layer "B.SilkS")
		)
		(fp_line
			(start -0.7874 0.4064)
			(end 0.7874 0.4064)
			(stroke
				(width 0.1524)
				(type default)
			)
			(layer "B.SilkS")
		)
		(fp_line
			(start 0 0.381)
			(end 0 -0.381)
			(stroke
				(width 0.1524)
				(type default)
			)
			(layer "B.SilkS")
		)
		(fp_line
			(start 0.7874 -0.4064)
			(end -0.7874 -0.4064)
			(stroke
				(width 0.1524)
				(type default)
			)
			(layer "B.SilkS")
		)
		(fp_line
			(start 0.7874 0.4064)
			(end 0.7874 -0.4064)
			(stroke
				(width 0.1524)
				(type default)
			)
			(layer "B.SilkS")
		)
		(fp_poly
			(pts
				(xy 0.5334 0.254) (xy 0.635 0.254) (xy 0.635 0.2286) (xy 0.635 -0.254) (xy 0.5334 -0.254) (xy 0.5334 -0.2794)
				(xy -0.5334 -0.2794) (xy -0.5334 -0.254) (xy -0.635 -0.254) (xy -0.635 0.254) (xy -0.5334 0.254)
				(xy -0.5334 0.2794) (xy 0.508 0.2794) (xy 0.5334 0.2794)
			)
			(stroke
				(width 0)
				(type default)
			)
			(fill no)
			(layer "B.CrtYd")
		)
		(pad "1" smd rect
			(at -0.40005 0 180)
			(size 0.4572 0.508)
			(layers "B.Cu" "B.Mask" "B.Paste")
			(net "P1V05_LAN1")
		)
		(pad "2" smd rect
			(at 0.40005 0 180)
			(size 0.4572 0.508)
			(layers "B.Cu" "B.Mask" "B.Paste")
			(net "GND")
		)
	)
	(footprint ""
		(layer "B.Cu")
		(at 68.633086 -131.280662 90)
		(property "Reference" "C256"
			(at -55.831486 -38.570662 270)
			(unlocked yes)
			(layer "B.SilkS")
			(effects
				(font
					(size 0.7874 0.5842)
					(thickness 0.1524)
				)
				(justify left mirror)
			)
		)
		(property "Value" ""
			(at 0 0 90)
			(layer "B.Fab")
			(effects
				(font
					(size 1.27 1.27)
				)
				(justify mirror)
			)
		)
		(duplicate_pad_numbers_are_jumpers no)
		(fp_line
			(start 0.7874 -0.4064)
			(end -0.7874 -0.4064)
			(stroke
				(width 0.1524)
				(type default)
			)
			(layer "B.SilkS")
		)
		(fp_line
			(start -0.7874 -0.4064)
			(end -0.7874 0.4064)
			(stroke
				(width 0.1524)
				(type default)
			)
			(layer "B.SilkS")
		)
		(fp_line
			(start 0 0.381)
			(end 0 -0.381)
			(stroke
				(width 0.1524)
				(type default)
			)
			(layer "B.SilkS")
		)
		(fp_line
			(start 0.7874 0.4064)
			(end 0.7874 -0.4064)
			(stroke
				(width 0.1524)
				(type default)
			)
			(layer "B.SilkS")
		)
		(fp_line
			(start -0.7874 0.4064)
			(end 0.7874 0.4064)
			(stroke
				(width 0.1524)
				(type default)
			)
			(layer "B.SilkS")
		)
		(fp_poly
			(pts
				(xy 0.5334 0.254) (xy 0.635 0.254) (xy 0.635 0.2286) (xy 0.635 -0.254) (xy 0.5334 -0.254) (xy 0.5334 -0.2794)
				(xy -0.5334 -0.2794) (xy -0.5334 -0.254) (xy -0.635 -0.254) (xy -0.635 0.254) (xy -0.5334 0.254)
				(xy -0.5334 0.2794) (xy 0.508 0.2794) (xy 0.5334 0.2794)
			)
			(stroke
				(width 0)
				(type default)
			)
			(fill no)
			(layer "B.CrtYd")
		)
		(pad "1" smd rect
			(at -0.40005 0 270)
			(size 0.4572 0.508)
			(layers "B.Cu" "B.Mask" "B.Paste")
			(net "P3V3_NODE1")
		)
		(pad "2" smd rect
			(at 0.40005 0 270)
			(size 0.4572 0.508)
			(layers "B.Cu" "B.Mask" "B.Paste")
			(net "GND")
		)
	)
	(footprint ""
		(layer "B.Cu")
		(at 58.53176 -185.205624 90)
		(property "Reference" "R922"
			(at 4.15163 0.268224 270)
			(unlocked yes)
			(layer "B.SilkS")
			(effects
				(font
					(size 0.7874 0.5842)
					(thickness 0.1524)
				)
				(justify left mirror)
			)
		)
		(property "Value" ""
			(at 0 0 90)
			(layer "B.Fab")
			(effects
				(font
					(size 1.27 1.27)
				)
				(justify mirror)
			)
		)
		(duplicate_pad_numbers_are_jumpers no)
		(fp_line
			(start 0.7874 -0.4064)
			(end -0.7874 -0.4064)
			(stroke
				(width 0.1524)
				(type default)
			)
			(layer "B.SilkS")
		)
		(fp_line
			(start -0.7874 -0.4064)
			(end -0.7874 0.4064)
			(stroke
				(width 0.1524)
				(type default)
			)
			(layer "B.SilkS")
		)
		(fp_line
			(start 0.7874 0.4064)
			(end 0.7874 -0.4064)
			(stroke
				(width 0.1524)
				(type default)
			)
			(layer "B.SilkS")
		)
		(fp_line
			(start -0.7874 0.4064)
			(end 0.7874 0.4064)
			(stroke
				(width 0.1524)
				(type default)
			)
			(layer "B.SilkS")
		)
		(fp_poly
			(pts
				(xy 0.508 0.2794) (xy 0.508 0.2286) (xy 0.635 0.2286) (xy 0.635 -0.254) (xy 0.5334 -0.254) (xy 0.5334 -0.2794)
				(xy -0.5334 -0.2794) (xy -0.5334 -0.254) (xy -0.635 -0.254) (xy -0.635 0.254) (xy -0.5334 0.254)
				(xy -0.5334 0.2794)
			)
			(stroke
				(width 0)
				(type default)
			)
			(fill no)
			(layer "B.CrtYd")
		)
		(pad "1" smd rect
			(at -0.40005 0 270)
			(size 0.4572 0.508)
			(layers "B.Cu" "B.Mask" "B.Paste")
			(net "UART_T1_NODE3_TXD")
		)
		(pad "2" smd rect
			(at 0.40005 0 270)
			(size 0.4572 0.508)
			(layers "B.Cu" "B.Mask" "B.Paste")
			(net "UART_T1_NODE3_TXD_R")
		)
	)
)
